(kicad_pcb
	(version 20221018)
	(generator pcbnew)
	(general
    (thickness 1.6)
  )
	(paper "A4")
	(title_block
    (title "NUC Computer Cluster Power Breakout HW")
    (date "2023-10-18")
    (rev "1.4.3")
    (company "Antmicro Ltd.")
		(comment 9 "footprints 154-158 of 234")
	)
	(layers
    (0 "F.Cu" mixed)
    (1 "In1.Cu" power)
    (2 "In2.Cu" mixed)
    (31 "B.Cu" power)
    (32 "B.Adhes" user "B.Adhesive")
    (33 "F.Adhes" user "F.Adhesive")
    (34 "B.Paste" user)
    (35 "F.Paste" user)
    (36 "B.SilkS" user "B.Silkscreen")
    (37 "F.SilkS" user "F.Silkscreen")
    (38 "B.Mask" user)
    (39 "F.Mask" user)
    (40 "Dwgs.User" user "User.Drawings")
    (41 "Cmts.User" user "User.Comments")
    (42 "Eco1.User" user "User.Eco1")
    (43 "Eco2.User" user "User.Eco2")
    (44 "Edge.Cuts" user)
    (45 "Margin" user)
    (46 "B.CrtYd" user "B.Courtyard")
    (47 "F.CrtYd" user "F.Courtyard")
    (48 "B.Fab" user)
    (49 "F.Fab" user)
  )
	(footprint "antmicro-footprints:TP_SMD_1mm" (layer "F.Cu")
    (at 189.15 107.65)
    (property "Author" "Antmicro")
    (property "License" "Apache-2.0")
    (property "MPN" "")
    (property "Manufacturer" "")
    (property "Sheetfile" "ftdi-module.kicad_sch")
    (property "Sheetname" "FTDI")
    (property "exclude_from_bom" "")
    (property "ki_description" "Test point 1mm SMD")
    (property "ki_keywords" "TESTPOINT")
    (attr exclude_from_pos_files exclude_from_bom)
    (fp_text reference "TP4" (at 0.4 -0.55 90) (layer "F.SilkS")
        (effects (font (size 0.7 0.7) (thickness 0.15)) (justify left bottom))
    )
    (fp_text value "TP_1mm_SMD" (at 0 1.4) (layer "F.Fab")
        (effects (font (size 0.7 0.7) (thickness 0.15)) (justify left bottom))
    )
    (fp_text user "${REFERENCE}" (at -0.5 2.8) (layer "F.Fab") hide
        (effects (font (size 0.7 0.7) (thickness 0.15)) (justify left bottom))
    )
    (fp_text user "Author: Antmicro" (at -0.5 4) (layer "F.Fab") hide
        (effects (font (size 0.7 0.7) (thickness 0.15)) (justify left bottom))
    )
    (fp_text user "License: Apache-2.0" (at -0.5 5.2) (layer "F.Fab") hide
        (effects (font (size 0.7 0.7) (thickness 0.15)) (justify left bottom))
    )
    (fp_circle (center 0 0) (end 0.6 0)
      (stroke (width 0.05) (type default)) (fill none) (layer "F.CrtYd"))
    (pad "1" smd circle (at 0 0) (size 1 1) (layers "F.Cu" "F.Mask")
      (net 114 "Net-(U1-CC_{2})") (pinfunction "1") (pintype "passive"))
  )
	(footprint "antmicro-footprints:LED_0603_1608Metric_G" (layer "F.Cu")
    (at 180.85 53.45)
    (descr "LED SMD 0603 Green")
    (tags "LED SMD 0603 Green")
    (property "Author" "Antmicro")
    (property "Color" "Green")
    (property "License" "Apache-2.0")
    (property "MPN" "LG L29K-G2J1-24-Z")
    (property "Manufacturer" "OSRAM")
    (property "Sheetfile" "d1600e-psu-breakout-board.kicad_sch")
    (property "Sheetname" "")
    (property "ki_description" "LED, Green, SMD, 0603, 20 mA, 1.7 V, 570 nm")
    (property "ki_keywords" "SMT, DIODE, SEMICONDUCTOR, LED")
    (zone_connect 1)
    (attr smd)
    (fp_text reference "D8" (at 1.2 0.45) (layer "F.SilkS")
        (effects (font (size 0.7 0.7) (thickness 0.15)) (justify left bottom))
    )
    (fp_text value "LED_G_0603_LG_L29K-G2J1-24-Z" (at -0.001 1.599) (layer "F.Fab")
        (effects (font (size 0.7 0.7) (thickness 0.15)) (justify left bottom))
    )
    (fp_text user "Author: Antmicro" (at -1.4224 4.799) (layer "F.Fab") hide
        (effects (font (size 0.7 0.7) (thickness 0.15)) (justify left bottom))
    )
    (fp_text user "License: Apache-2.0" (at -1.4224 3.599) (layer "F.Fab") hide
        (effects (font (size 0.7 0.7) (thickness 0.15)) (justify left bottom))
    )
    (fp_text user "${REFERENCE}" (at -1.4224 5.999) (layer "F.Fab") hide
        (effects (font (size 0.7 0.7) (thickness 0.15)) (justify left bottom))
    )
    (fp_line (start -1.18 -0.319) (end -1.18 0.321)
      (stroke (width 0.15) (type solid)) (layer "F.SilkS"))
    (fp_line (start -0.094672 0.001008) (end -0.24 0.001008)
      (stroke (width 0.1) (type solid)) (layer "F.SilkS"))
    (fp_line (start -0.094672 0.001008) (end 0.105328 -0.198992)
      (stroke (width 0.1) (type solid)) (layer "F.SilkS"))
    (fp_line (start -0.094672 0.201008) (end -0.094672 -0.198992)
      (stroke (width 0.1) (type solid)) (layer "F.SilkS"))
    (fp_line (start 0.105328 0.001008) (end 0.24 0.001)
      (stroke (width 0.1) (type solid)) (layer "F.SilkS"))
    (fp_line (start 0.105328 0.201008) (end -0.094672 0.001008)
      (stroke (width 0.1) (type solid)) (layer "F.SilkS"))
    (fp_line (start 0.105328 0.201008) (end 0.105328 -0.198992)
      (stroke (width 0.1) (type solid)) (layer "F.SilkS"))
    (fp_line (start 0.22 -0.35) (end -0.22 -0.35)
      (stroke (width 0.15) (type solid)) (layer "F.SilkS"))
    (fp_line (start 0.22 0.35) (end -0.22 0.35)
      (stroke (width 0.15) (type solid)) (layer "F.SilkS"))
    (fp_rect (start 1.25 0.65) (end -1.25 -0.65)
      (stroke (width 0.05) (type solid)) (fill none) (layer "F.CrtYd"))
    (fp_line (start -0.199 -0.202) (end -0.199 0.1)
      (stroke (width 0.15) (type solid)) (layer "F.Fab"))
    (fp_line (start -0.199 0) (end -0.597 0)
      (stroke (width 0.15) (type solid)) (layer "F.Fab"))
    (fp_line (start -0.199 0.2) (end -0.199 0.1)
      (stroke (width 0.15) (type solid)) (layer "F.Fab"))
    (fp_line (start -0.101 0) (end 0.201 0.2)
      (stroke (width 0.15) (type solid)) (layer "F.Fab"))
    (fp_line (start 0.201 -0.202) (end -0.101 0)
      (stroke (width 0.15) (type solid)) (layer "F.Fab"))
    (fp_line (start 0.201 0) (end 0.201 -0.202)
      (stroke (width 0.15) (type solid)) (layer "F.Fab"))
    (fp_line (start 0.201 0.2) (end 0.201 0)
      (stroke (width 0.15) (type solid)) (layer "F.Fab"))
    (fp_line (start 0.599 0) (end 0.201 0)
      (stroke (width 0.15) (type solid)) (layer "F.Fab"))
    (fp_rect (start 0.848 0.4) (end -0.85 -0.402)
      (stroke (width 0.15) (type solid)) (fill none) (layer "F.Fab"))
    (pad "1" smd roundrect (at -0.7 0 180) (size 0.8 1) (layers "F.Cu" "F.Paste" "F.Mask") (roundrect_rratio 0.2)
      (net 4 "GND") (pinfunction "C") (pintype "passive"))
    (pad "2" smd roundrect (at 0.7 0 180) (size 0.8 1) (layers "F.Cu" "F.Paste" "F.Mask") (roundrect_rratio 0.2)
      (net 53 "Net-(D8-A)") (pinfunction "A") (pintype "passive"))
  )
	(footprint "antmicro-footprints:Conn_Molex_KK_1x4_22-27-2041" (layer "F.Cu")
    (at 152.37 53.99)
    (property "Author" "Antmicro")
    (property "License" "Apache-2.0")
    (property "MPN" "22-27-2041")
    (property "Manufacturer" "Molex")
    (property "Sheetfile" "d1600e-psu-breakout-board.kicad_sch")
    (property "Sheetname" "")
    (property "ki_description" "Rectangular connector (header, female pins)")
    (property "ki_keywords" "VERTICAL, THT, HEADER, CONNECTOR, MALE")
    (attr through_hole)
    (fp_text reference "J13" (at 4.255 4.21) (layer "F.SilkS")
        (effects (font (size 0.7 0.7) (thickness 0.15)) (justify left bottom))
    )
    (fp_text value "Molex_KK_1x4_22-27-2041" (at -0.8 4.6 180) (layer "F.Fab")
        (effects (font (size 0.7 0.7) (thickness 0.15)) (justify left bottom))
    )
    (fp_text user "License: Apache-2.0" (at -2.12 7.95) (layer "F.Fab") hide
        (effects (font (size 0.7 0.7) (thickness 0.15)) (justify left bottom))
    )
    (fp_text user "${REFERENCE}" (at -2.12 9.15) (layer "F.Fab") hide
        (effects (font (size 0.7 0.7) (thickness 0.15)) (justify left bottom))
    )
    (fp_text user "Author: Antmicro" (at -2.12 6.75) (layer "F.Fab") hide
        (effects (font (size 0.7 0.7) (thickness 0.15)) (justify left bottom))
    )
    (fp_line (start -1.39 -3.03) (end -1.39 2.99)
      (stroke (width 0.15) (type solid)) (layer "F.SilkS"))
    (fp_line (start -1.39 2.99) (end 8.99 2.99)
      (stroke (width 0.15) (type solid)) (layer "F.SilkS"))
    (fp_line (start -0.81 -3.03) (end -0.81 -2.43)
      (stroke (width 0.15) (type solid)) (layer "F.SilkS"))
    (fp_line (start -0.81 -2.43) (end 0.79 -2.43)
      (stroke (width 0.15) (type solid)) (layer "F.SilkS"))
    (fp_line (start -0.01 1.99) (end 0.24 1.46)
      (stroke (width 0.15) (type solid)) (layer "F.SilkS"))
    (fp_line (start -0.01 1.99) (end 7.61 1.99)
      (stroke (width 0.15) (type solid)) (layer "F.SilkS"))
    (fp_line (start -0.01 2.99) (end -0.01 1.99)
      (stroke (width 0.15) (type solid)) (layer "F.SilkS"))
    (fp_line (start 0.24 1.46) (end 7.36 1.46)
      (stroke (width 0.15) (type solid)) (layer "F.SilkS"))
    (fp_line (start 0.24 2.99) (end 0.24 1.99)
      (stroke (width 0.15) (type solid)) (layer "F.SilkS"))
    (fp_line (start 0.79 -2.43) (end 0.79 -3.03)
      (stroke (width 0.15) (type solid)) (layer "F.SilkS"))
    (fp_line (start 1.73 -3.03) (end 1.73 -2.43)
      (stroke (width 0.15) (type solid)) (layer "F.SilkS"))
    (fp_line (start 1.73 -2.43) (end 3.33 -2.43)
      (stroke (width 0.15) (type solid)) (layer "F.SilkS"))
    (fp_line (start 3.33 -2.43) (end 3.33 -3.03)
      (stroke (width 0.15) (type solid)) (layer "F.SilkS"))
    (fp_line (start 4.27 -3.03) (end 4.27 -2.43)
      (stroke (width 0.15) (type solid)) (layer "F.SilkS"))
    (fp_line (start 4.27 -2.43) (end 5.87 -2.43)
      (stroke (width 0.15) (type solid)) (layer "F.SilkS"))
    (fp_line (start 5.87 -2.43) (end 5.87 -3.03)
      (stroke (width 0.15) (type solid)) (layer "F.SilkS"))
    (fp_line (start 6.81 -3.03) (end 6.81 -2.43)
      (stroke (width 0.15) (type solid)) (layer "F.SilkS"))
    (fp_line (start 6.81 -2.43) (end 8.41 -2.43)
      (stroke (width 0.15) (type solid)) (layer "F.SilkS"))
    (fp_line (start 7.36 1.46) (end 7.61 1.99)
      (stroke (width 0.15) (type solid)) (layer "F.SilkS"))
    (fp_line (start 7.36 2.99) (end 7.36 1.99)
      (stroke (width 0.15) (type solid)) (layer "F.SilkS"))
    (fp_line (start 7.61 1.99) (end 7.61 2.99)
      (stroke (width 0.15) (type solid)) (layer "F.SilkS"))
    (fp_line (start 8.41 -2.43) (end 8.41 -3.03)
      (stroke (width 0.15) (type solid)) (layer "F.SilkS"))
    (fp_line (start 8.99 -3.03) (end -1.39 -3.03)
      (stroke (width 0.15) (type solid)) (layer "F.SilkS"))
    (fp_line (start 8.99 2.99) (end 8.99 -3.03)
      (stroke (width 0.15) (type solid)) (layer "F.SilkS"))
    (fp_line (start -1.79 -3.38) (end -1.79 3.42)
      (stroke (width 0.05) (type solid)) (layer "F.CrtYd"))
    (fp_line (start -1.79 3.42) (end 9.37 3.42)
      (stroke (width 0.05) (type solid)) (layer "F.CrtYd"))
    (fp_line (start 9.37 -3.38) (end -1.79 -3.38)
      (stroke (width 0.05) (type solid)) (layer "F.CrtYd"))
    (fp_line (start 9.37 3.42) (end 9.37 -3.38)
      (stroke (width 0.05) (type solid)) (layer "F.CrtYd"))
    (fp_line (start -1.29 -2.88) (end -1.29 2.92)
      (stroke (width 0.15) (type solid)) (layer "F.Fab"))
    (fp_line (start -1.29 2.92) (end 8.87 2.92)
      (stroke (width 0.15) (type solid)) (layer "F.Fab"))
    (fp_line (start 8.163 0) (end 8.87 -0.5)
      (stroke (width 0.15) (type solid)) (layer "F.Fab"))
    (fp_line (start 8.87 -2.88) (end -1.29 -2.88)
      (stroke (width 0.15) (type solid)) (layer "F.Fab"))
    (fp_line (start 8.87 0.5) (end 8.163 0)
      (stroke (width 0.15) (type solid)) (layer "F.Fab"))
    (fp_line (start 8.87 2.92) (end 8.87 -2.88)
      (stroke (width 0.15) (type solid)) (layer "F.Fab"))
    (pad "1" thru_hole roundrect (at 0 0) (size 1.74 2.19) (drill 1.19) (layers "*.Cu" "*.Mask") (roundrect_rratio 0.143678)
      (net 11 "VCC12V0") (pintype "passive"))
    (pad "2" thru_hole oval (at 2.54 0) (size 1.74 2.19) (drill 1.19) (layers "*.Cu" "*.Mask")
      (net 4 "GND") (pintype "passive"))
    (pad "3" thru_hole oval (at 5.08 0) (size 1.74 2.19) (drill 1.19) (layers "*.Cu" "*.Mask")
      (net 4 "GND") (pintype "passive"))
    (pad "4" thru_hole oval (at 7.62 0) (size 1.74 2.19) (drill 1.19) (layers "*.Cu" "*.Mask")
      (net 2 "VCC5V0") (pintype "passive"))
  )
	(footprint "antmicro-footprints:SOIC-4_4.55x2.6mm_P1.27mm" (layer "F.Cu")
    (at 166.95 106.85 90)
    (descr "ACPL-217-500E")
    (tags "Integrated Circuit")
    (property "Author" "Antmicro")
    (property "Description" "Broadcom ACPL-217-500E DC Input Transistor Output Optocoupler, Surface Mount, 4-Pin SO")
    (property "License" "Apache-2.0")
    (property "MPN" "ACPL-217-500E")
    (property "Manufacturer" "Broadcom")
    (property "Sheetfile" "ftdi-module.kicad_sch")
    (property "Sheetname" "FTDI")
    (property "ki_description" "Optocoupler, Transistor Output, 1 Channel, SOIC, 4 Pins, 50 mA, 3 kV, 50 %")
    (property "ki_keywords" "SMT, OPTOCOUPLER, IC")
    (attr smd)
    (fp_text reference "U7" (at -4.25 -1.9 90) (layer "F.SilkS")
        (effects (font (size 0.7 0.7) (thickness 0.15)) (justify left bottom))
    )
    (fp_text value "ACPL-217-500E" (at -4.25 2.75 90) (layer "F.Fab")
        (effects (font (size 0.7 0.7) (thickness 0.15)) (justify left bottom))
    )
    (fp_text user "." (at -2.7 -1.6 90) (layer "F.SilkS")
        (effects (font (size 1 1) (thickness 0.15)))
    )
    (fp_text user "${REFERENCE}" (at -4.3 4.25 90) (layer "F.Fab") hide
        (effects (font (size 0.7 0.7) (thickness 0.15)) (justify left bottom))
    )
    (fp_text user "Author: Antmicro" (at -4.3 5.5 90) (layer "F.Fab") hide
        (effects (font (size 0.7 0.7) (thickness 0.15)) (justify left bottom))
    )
    (fp_text user "License: Apache-2.0" (at -4.25 7 90) (layer "F.Fab") hide
        (effects (font (size 0.7 0.7) (thickness 0.15)) (justify left bottom))
    )
    (fp_line (start -2.3 -1.4) (end -1.8 -1.4)
      (stroke (width 0.12) (type solid)) (layer "F.SilkS"))
    (fp_line (start -2.3 1.1) (end -2.3 1.4)
      (stroke (width 0.12) (type solid)) (layer "F.SilkS"))
    (fp_line (start -1.8 1.4) (end -2.3 1.4)
      (stroke (width 0.12) (type solid)) (layer "F.SilkS"))
    (fp_line (start 1.8 -1.4) (end 2.3 -1.4)
      (stroke (width 0.12) (type solid)) (layer "F.SilkS"))
    (fp_line (start 2.3 -1.1) (end 2.3 -1.4)
      (stroke (width 0.12) (type solid)) (layer "F.SilkS"))
    (fp_line (start 2.3 1.1) (end 2.3 1.4)
      (stroke (width 0.12) (type solid)) (layer "F.SilkS"))
    (fp_line (start 2.3 1.4) (end 1.8 1.4)
      (stroke (width 0.12) (type solid)) (layer "F.SilkS"))
    (fp_line (start -4.3 -1.7) (end 4.29 -1.7)
      (stroke (width 0.05) (type solid)) (layer "F.CrtYd"))
    (fp_line (start -4.3 1.69) (end -4.3 -1.7)
      (stroke (width 0.05) (type solid)) (layer "F.CrtYd"))
    (fp_line (start 4.29 -1.7) (end 4.29 1.69)
      (stroke (width 0.05) (type solid)) (layer "F.CrtYd"))
    (fp_line (start 4.29 1.69) (end -4.3 1.69)
      (stroke (width 0.05) (type solid)) (layer "F.CrtYd"))
    (fp_line (start -2.201 -1.301) (end 2.2 -1.301)
      (stroke (width 0.15) (type solid)) (layer "F.Fab"))
    (fp_line (start -2.201 -0.03) (end -0.931 -1.301)
      (stroke (width 0.15) (type solid)) (layer "F.Fab"))
    (fp_line (start -2.201 1.3) (end -2.201 -1.301)
      (stroke (width 0.15) (type solid)) (layer "F.Fab"))
    (fp_line (start 2.2 -1.301) (end 2.2 1.3)
      (stroke (width 0.15) (type solid)) (layer "F.Fab"))
    (fp_line (start 2.2 1.3) (end -2.201 1.3)
      (stroke (width 0.15) (type solid)) (layer "F.Fab"))
    (pad "1" smd roundrect (at -3.125 -0.635 180) (size 0.65 1.85) (layers "F.Cu" "F.Paste" "F.Mask") (roundrect_rratio 0.15)
      (net 116 "Net-(U5-BDBUS1)") (pintype "passive"))
    (pad "2" smd roundrect (at -3.125 0.634 180) (size 0.65 1.85) (layers "F.Cu" "F.Paste" "F.Mask") (roundrect_rratio 0.15)
      (net 147 "Net-(R74-Pad2)") (pintype "passive"))
    (pad "3" smd roundrect (at 3.124 0.634 180) (size 0.65 1.85) (layers "F.Cu" "F.Paste" "F.Mask") (roundrect_rratio 0.15)
      (net 4 "GND") (pintype "passive"))
    (pad "4" smd roundrect (at 3.124 -0.635 180) (size 0.65 1.85) (layers "F.Cu" "F.Paste" "F.Mask") (roundrect_rratio 0.15)
      (net 115 "Net-(U6-A)") (pintype "passive"))
  )
	(footprint "antmicro-footprints:Vishay_PowerPAK_1212-8_Single" (layer "F.Cu")
    (at 171.1 86.2 90)
    (descr "PowerPAK 1212-8 Single")
    (tags "Vishay PowerPAK 1212-8 Single")
    (property "Author" "Antmicro")
    (property "License" "Apache-2.0")
    (property "MPN" "SI7613DN-T1-GE3")
    (property "Manufacturer" "Vishay")
    (property "Sheetfile" "power-switch.kicad_sch")
    (property "Sheetname" "Power switch 4")
    (property "ki_description" "Power MOSFET, P Channel, 20 V, 35 A, 0.0072 ohm, PowerPAK 1212, Surface Mount")
    (property "ki_keywords" "SMT, TRANSISTOR, SEMICONDUCTOR, MOSFET, PMOS")
    (attr smd)
    (fp_text reference "QB4" (at -2.95 0.25 180) (layer "F.SilkS")
        (effects (font (size 0.7 0.7) (thickness 0.15)) (justify left bottom))
    )
    (fp_text value "SI7613DN-T1-GE3" (at 0 2.7 90) (layer "F.Fab")
        (effects (font (size 0.7 0.7) (thickness 0.15)) (justify left bottom))
    )
    (fp_text user "Author: Antmicro" (at -8 5.9 90) (layer "F.Fab") hide
        (effects (font (size 0.7 0.7) (thickness 0.15)) (justify left bottom))
    )
    (fp_text user "License: Apache-2.0" (at -8 7.1 90) (layer "F.Fab") hide
        (effects (font (size 0.7 0.7) (thickness 0.15)) (justify left bottom))
    )
    (fp_text user "${REFERENCE}" (at -8 4.7 90) (layer "F.Fab") hide
        (effects (font (size 0.7 0.7) (thickness 0.15)) (justify left bottom))
    )
    (fp_line (start -1.651 -1.651) (end -1.651 -1.317)
      (stroke (width 0.15) (type solid)) (layer "F.SilkS"))
    (fp_line (start -1.651 -1.651) (end 1.648 -1.651)
      (stroke (width 0.15) (type solid)) (layer "F.SilkS"))
    (fp_line (start -1.635 1.3) (end -1.635 1.634)
      (stroke (width 0.15) (type solid)) (layer "F.SilkS"))
    (fp_line (start -1.635 1.634) (end 1.634 1.634)
      (stroke (width 0.15) (type solid)) (layer "F.SilkS"))
    (fp_line (start 1.634 1.3) (end 1.634 1.634)
      (stroke (width 0.15) (type solid)) (layer "F.SilkS"))
    (fp_line (start 1.648 -1.651) (end 1.648 -1.317)
      (stroke (width 0.15) (type solid)) (layer "F.SilkS"))
    (fp_circle (center -1.9 -1.4) (end -1.85 -1.4)
      (stroke (width 0.15) (type solid)) (fill solid) (layer "F.SilkS"))
    (fp_rect (start -2 -1.8) (end 2 1.798)
      (stroke (width 0.05) (type solid)) (fill none) (layer "F.CrtYd"))
    (fp_line (start -1.6425 -1.4175) (end -1.4175 -1.6425)
      (stroke (width 0.15) (type solid)) (layer "F.Fab"))
    (fp_rect (start -1.651 -1.651) (end 1.648 1.648)
      (stroke (width 0.15) (type solid)) (fill none) (layer "F.Fab"))
    (pad "1" smd rect (at -1.436 -0.99 90) (size 0.99 0.405) (layers "F.Cu" "F.Paste" "F.Mask")
      (net 11 "VCC12V0") (pinfunction "S") (pintype "passive"))
    (pad "2" smd rect (at -1.436 -0.332 90) (size 0.99 0.405) (layers "F.Cu" "F.Paste" "F.Mask")
      (net 11 "VCC12V0") (pinfunction "S") (pintype "passive"))
    (pad "3" smd rect (at -1.436 0.33 90) (size 0.99 0.405) (layers "F.Cu" "F.Paste" "F.Mask")
      (net 11 "VCC12V0") (pinfunction "S") (pintype "passive"))
    (pad "4" smd rect (at -1.436 0.988 90) (size 0.99 0.405) (layers "F.Cu" "F.Paste" "F.Mask")
      (net 102 "Net-(QB4-G)") (pinfunction "G") (pintype "passive"))
    (pad "5" smd custom (at 0.557 0 90) (size 1.725 2.235) (layers "F.Cu" "F.Paste" "F.Mask")
      (net 27 "C_MEAS_4") (pinfunction "D") (pintype "passive") (zone_connect 2)
      (options (clearance outline) (anchor rect))
      (primitives
        (gr_poly
          (pts
            (xy 0.8625 0.1275)
            (xy 0.8625 -0.1275)
            (xy 1.3725 -0.1275)
            (xy 1.3725 -0.5325)
            (xy 0.8625 -0.5325)
            (xy 0.8625 -0.7875)
            (xy 1.3725 -0.7875)
            (xy 1.3725 -1.195)
            (xy 0.6125 -1.195)
            (xy 0.6125 1.195)
            (xy 1.3725 1.195)
            (xy 1.3725 0.7875)
            (xy 0.8625 0.7875)
            (xy 0.8625 0.5325)
            (xy 1.3725 0.5325)
            (xy 1.3725 0.1275)
          )
          (width 0) (fill yes))
      ))
  )
)
